(kicad_pcb
	(version 20260206)
	(generator "pcbnew")
	(generator_version "10.0")
	(general
		(thickness 1.6)
		(legacy_teardrops no)
	)
	(paper "A4")
	(title_block
		(title "04192023_DAF0TMB3IC0_F0TG_MB_C_brd_V02_OCP.brd")
		(comment 1 "Grand Teton / footprints 7288-7294 of 8354")
	)
	(layers
		(0 "F.Cu" signal "TOP")
		(4 "In1.Cu" signal "GND")
		(6 "In2.Cu" signal "IN1")
		(8 "In3.Cu" signal "GND1")
		(10 "In4.Cu" signal "IN2")
		(12 "In5.Cu" signal "GND2")
		(14 "In6.Cu" signal "IN3")
		(16 "In7.Cu" signal "GND3")
		(18 "In8.Cu" signal "VCC")
		(20 "In9.Cu" signal "VCC1")
		(22 "In10.Cu" signal "GND4")
		(24 "In11.Cu" signal "IN4")
		(26 "In12.Cu" signal "GND5")
		(28 "In13.Cu" signal "IN5")
		(30 "In14.Cu" signal "GND6")
		(32 "In15.Cu" signal "IN6")
		(34 "In16.Cu" signal "GND7")
		(2 "B.Cu" signal "BOTTOM")
		(9 "F.Adhes" user "F.Adhesive")
		(11 "B.Adhes" user "B.Adhesive")
		(13 "F.Paste" user "Package Geometry/Pastemask Top")
		(15 "B.Paste" user "Package Geometry/Pastemask Bottom")
		(5 "F.SilkS" user "Ref Des/Silkscreen Top")
		(7 "B.SilkS" user "Ref Des/Silkscreen Bottom")
		(1 "F.Mask" user "Board Geometry/Soldermask Top")
		(3 "B.Mask" user "Board Geometry/Soldermask Bottom")
		(17 "Dwgs.User" user "User.Drawings")
		(19 "Cmts.User" user "User.Comments")
		(21 "Eco1.User" user "User.Eco1")
		(23 "Eco2.User" user "User.Eco2")
		(25 "Edge.Cuts" user "Board Geometry/Outline")
		(27 "Margin" user)
		(31 "F.CrtYd" user "Package Geometry/Place Bound Top")
		(29 "B.CrtYd" user "Package Geometry/Place Bound Bottom")
		(35 "F.Fab" user "Ref Des/Assembly Top")
		(33 "B.Fab" user "Ref Des/Assembly Bottom")
	)
	(footprint ""
		(layer "B.Cu")
		(at 161.09188 -15.35811 90)
		(property "Reference" "R4509"
			(at 0 0 90)
			(layer "B.SilkS")
			(hide yes)
			(effects
				(font
					(size 1.27 1.27)
				)
				(justify mirror)
			)
		)
		(property "Value" ""
			(at 0 0 90)
			(layer "B.Fab")
			(effects
				(font
					(size 1.27 1.27)
				)
				(justify mirror)
			)
		)
		(duplicate_pad_numbers_are_jumpers no)
		(fp_line
			(start 0.7874 -0.4064)
			(end -0.7874 -0.4064)
			(stroke
				(width 0.1524)
				(type default)
			)
			(layer "B.SilkS")
		)
		(fp_line
			(start -0.7874 -0.4064)
			(end -0.7874 0.4064)
			(stroke
				(width 0.1524)
				(type default)
			)
			(layer "B.SilkS")
		)
		(fp_line
			(start 0.7874 0.4064)
			(end 0.7874 -0.4064)
			(stroke
				(width 0.1524)
				(type default)
			)
			(layer "B.SilkS")
		)
		(fp_line
			(start -0.7874 0.4064)
			(end 0.7874 0.4064)
			(stroke
				(width 0.1524)
				(type default)
			)
			(layer "B.SilkS")
		)
		(fp_line
			(start 0.67945 -0.305054)
			(end 0.12065 -0.305054)
			(stroke
				(width 0.1)
				(type default)
			)
			(layer "B.Fab")
		)
		(fp_line
			(start 0.12065 -0.305054)
			(end 0.12065 -0.2794)
			(stroke
				(width 0.1)
				(type default)
			)
			(layer "B.Fab")
		)
		(fp_line
			(start -0.12065 -0.3048)
			(end -0.67945 -0.3048)
			(stroke
				(width 0.1)
				(type default)
			)
			(layer "B.Fab")
		)
		(fp_line
			(start -0.67945 -0.3048)
			(end -0.67945 0.3048)
			(stroke
				(width 0.1)
				(type default)
			)
			(layer "B.Fab")
		)
		(fp_line
			(start 0.12065 -0.2794)
			(end -0.12065 -0.2794)
			(stroke
				(width 0.1)
				(type default)
			)
			(layer "B.Fab")
		)
		(fp_line
			(start -0.12065 -0.2794)
			(end -0.12065 -0.3048)
			(stroke
				(width 0.1)
				(type default)
			)
			(layer "B.Fab")
		)
		(fp_line
			(start 0.12065 0.2794)
			(end 0.12065 0.3048)
			(stroke
				(width 0.1)
				(type default)
			)
			(layer "B.Fab")
		)
		(fp_line
			(start -0.120396 0.2794)
			(end 0.12065 0.2794)
			(stroke
				(width 0.1)
				(type default)
			)
			(layer "B.Fab")
		)
		(fp_line
			(start 0.67945 0.3048)
			(end 0.67945 -0.305054)
			(stroke
				(width 0.1)
				(type default)
			)
			(layer "B.Fab")
		)
		(fp_line
			(start 0.12065 0.3048)
			(end 0.67945 0.3048)
			(stroke
				(width 0.1)
				(type default)
			)
			(layer "B.Fab")
		)
		(fp_line
			(start -0.120396 0.3048)
			(end -0.120396 0.2794)
			(stroke
				(width 0.1)
				(type default)
			)
			(layer "B.Fab")
		)
		(fp_line
			(start -0.67945 0.3048)
			(end -0.120396 0.3048)
			(stroke
				(width 0.1)
				(type default)
			)
			(layer "B.Fab")
		)
		(pad "1" smd circle
			(at 0.40005 0 270)
			(size 0 0)
			(layers "B.Cu" "B.Mask" "B.Paste")
			(net "SMB_1_PLD_3V3AUX_SDA")
		)
		(pad "2" smd circle
			(at -0.40005 0 270)
			(size 0 0)
			(layers "B.Cu" "B.Mask" "B.Paste")
			(net "SMB_1_PLD_3V3AUX_SDA_R3")
		)
	)
	(footprint ""
		(layer "B.Cu")
		(at 71.809864 -11.26871 -90)
		(property "Reference" "R3162"
			(at 0 0 90)
			(layer "B.SilkS")
			(hide yes)
			(effects
				(font
					(size 1.27 1.27)
				)
				(justify mirror)
			)
		)
		(property "Value" ""
			(at 0 0 90)
			(layer "B.Fab")
			(effects
				(font
					(size 1.27 1.27)
				)
				(justify mirror)
			)
		)
		(duplicate_pad_numbers_are_jumpers no)
		(fp_line
			(start -0.7874 0.4064)
			(end 0.7874 0.4064)
			(stroke
				(width 0.1524)
				(type default)
			)
			(layer "B.SilkS")
		)
		(fp_line
			(start 0.7874 0.4064)
			(end 0.7874 -0.4064)
			(stroke
				(width 0.1524)
				(type default)
			)
			(layer "B.SilkS")
		)
		(fp_line
			(start -0.7874 -0.4064)
			(end -0.7874 0.4064)
			(stroke
				(width 0.1524)
				(type default)
			)
			(layer "B.SilkS")
		)
		(fp_line
			(start 0.7874 -0.4064)
			(end -0.7874 -0.4064)
			(stroke
				(width 0.1524)
				(type default)
			)
			(layer "B.SilkS")
		)
		(fp_line
			(start -0.67945 0.3048)
			(end -0.120396 0.3048)
			(stroke
				(width 0.1)
				(type default)
			)
			(layer "B.Fab")
		)
		(fp_line
			(start -0.120396 0.3048)
			(end -0.120396 0.2794)
			(stroke
				(width 0.1)
				(type default)
			)
			(layer "B.Fab")
		)
		(fp_line
			(start 0.12065 0.3048)
			(end 0.67945 0.3048)
			(stroke
				(width 0.1)
				(type default)
			)
			(layer "B.Fab")
		)
		(fp_line
			(start 0.67945 0.3048)
			(end 0.67945 -0.305054)
			(stroke
				(width 0.1)
				(type default)
			)
			(layer "B.Fab")
		)
		(fp_line
			(start -0.120396 0.2794)
			(end 0.12065 0.2794)
			(stroke
				(width 0.1)
				(type default)
			)
			(layer "B.Fab")
		)
		(fp_line
			(start 0.12065 0.2794)
			(end 0.12065 0.3048)
			(stroke
				(width 0.1)
				(type default)
			)
			(layer "B.Fab")
		)
		(fp_line
			(start -0.12065 -0.2794)
			(end -0.12065 -0.3048)
			(stroke
				(width 0.1)
				(type default)
			)
			(layer "B.Fab")
		)
		(fp_line
			(start 0.12065 -0.2794)
			(end -0.12065 -0.2794)
			(stroke
				(width 0.1)
				(type default)
			)
			(layer "B.Fab")
		)
		(fp_line
			(start -0.67945 -0.3048)
			(end -0.67945 0.3048)
			(stroke
				(width 0.1)
				(type default)
			)
			(layer "B.Fab")
		)
		(fp_line
			(start -0.12065 -0.3048)
			(end -0.67945 -0.3048)
			(stroke
				(width 0.1)
				(type default)
			)
			(layer "B.Fab")
		)
		(fp_line
			(start 0.12065 -0.305054)
			(end 0.12065 -0.2794)
			(stroke
				(width 0.1)
				(type default)
			)
			(layer "B.Fab")
		)
		(fp_line
			(start 0.67945 -0.305054)
			(end 0.12065 -0.305054)
			(stroke
				(width 0.1)
				(type default)
			)
			(layer "B.Fab")
		)
		(pad "1" smd circle
			(at 0.40005 0 90)
			(size 0 0)
			(layers "B.Cu" "B.Mask" "B.Paste")
			(net "P3V3_OCP_V3_2")
		)
		(pad "2" smd circle
			(at -0.40005 0 90)
			(size 0 0)
			(layers "B.Cu" "B.Mask" "B.Paste")
			(net "OCP_V3_2_ID0")
		)
	)
	(footprint ""
		(layer "B.Cu")
		(at 194.945 -97.119948 90)
		(property "Reference" "R6062"
			(at 0 0 90)
			(layer "B.SilkS")
			(hide yes)
			(effects
				(font
					(size 1.27 1.27)
				)
				(justify mirror)
			)
		)
		(property "Value" ""
			(at 0 0 90)
			(layer "B.Fab")
			(effects
				(font
					(size 1.27 1.27)
				)
				(justify mirror)
			)
		)
		(duplicate_pad_numbers_are_jumpers no)
		(fp_line
			(start 0.7874 -0.4064)
			(end -0.7874 -0.4064)
			(stroke
				(width 0.1524)
				(type default)
			)
			(layer "B.SilkS")
		)
		(fp_line
			(start -0.7874 -0.4064)
			(end -0.7874 0.4064)
			(stroke
				(width 0.1524)
				(type default)
			)
			(layer "B.SilkS")
		)
		(fp_line
			(start 0.7874 0.4064)
			(end 0.7874 -0.4064)
			(stroke
				(width 0.1524)
				(type default)
			)
			(layer "B.SilkS")
		)
		(fp_line
			(start -0.7874 0.4064)
			(end 0.7874 0.4064)
			(stroke
				(width 0.1524)
				(type default)
			)
			(layer "B.SilkS")
		)
		(fp_line
			(start 0.67945 -0.305054)
			(end 0.12065 -0.305054)
			(stroke
				(width 0.1)
				(type default)
			)
			(layer "B.Fab")
		)
		(fp_line
			(start 0.12065 -0.305054)
			(end 0.12065 -0.2794)
			(stroke
				(width 0.1)
				(type default)
			)
			(layer "B.Fab")
		)
		(fp_line
			(start -0.12065 -0.3048)
			(end -0.67945 -0.3048)
			(stroke
				(width 0.1)
				(type default)
			)
			(layer "B.Fab")
		)
		(fp_line
			(start -0.67945 -0.3048)
			(end -0.67945 0.3048)
			(stroke
				(width 0.1)
				(type default)
			)
			(layer "B.Fab")
		)
		(fp_line
			(start 0.12065 -0.2794)
			(end -0.12065 -0.2794)
			(stroke
				(width 0.1)
				(type default)
			)
			(layer "B.Fab")
		)
		(fp_line
			(start -0.12065 -0.2794)
			(end -0.12065 -0.3048)
			(stroke
				(width 0.1)
				(type default)
			)
			(layer "B.Fab")
		)
		(fp_line
			(start 0.12065 0.2794)
			(end 0.12065 0.3048)
			(stroke
				(width 0.1)
				(type default)
			)
			(layer "B.Fab")
		)
		(fp_line
			(start -0.120396 0.2794)
			(end 0.12065 0.2794)
			(stroke
				(width 0.1)
				(type default)
			)
			(layer "B.Fab")
		)
		(fp_line
			(start 0.67945 0.3048)
			(end 0.67945 -0.305054)
			(stroke
				(width 0.1)
				(type default)
			)
			(layer "B.Fab")
		)
		(fp_line
			(start 0.12065 0.3048)
			(end 0.67945 0.3048)
			(stroke
				(width 0.1)
				(type default)
			)
			(layer "B.Fab")
		)
		(fp_line
			(start -0.120396 0.3048)
			(end -0.120396 0.2794)
			(stroke
				(width 0.1)
				(type default)
			)
			(layer "B.Fab")
		)
		(fp_line
			(start -0.67945 0.3048)
			(end -0.120396 0.3048)
			(stroke
				(width 0.1)
				(type default)
			)
			(layer "B.Fab")
		)
		(pad "1" smd circle
			(at 0.40005 0 270)
			(size 0 0)
			(layers "B.Cu" "B.Mask" "B.Paste")
			(net "P3V3_OCP_V3_2_EN_R")
		)
		(pad "2" smd circle
			(at -0.40005 0 270)
			(size 0 0)
			(layers "B.Cu" "B.Mask" "B.Paste")
			(net "P3V3_AUX")
		)
	)
	(footprint ""
		(layer "B.Cu")
		(at 413.806132 -395.148562 90)
		(property "Reference" "C676"
			(at 0 0 90)
			(layer "B.SilkS")
			(hide yes)
			(effects
				(font
					(size 1.27 1.27)
				)
				(justify mirror)
			)
		)
		(property "Value" ""
			(at 0 0 90)
			(layer "B.Fab")
			(effects
				(font
					(size 1.27 1.27)
				)
				(justify mirror)
			)
		)
		(duplicate_pad_numbers_are_jumpers no)
		(fp_line
			(start 0.299974 -0.150114)
			(end -0.299974 -0.150114)
			(stroke
				(width 0.1)
				(type default)
			)
			(layer "B.Fab")
		)
		(fp_line
			(start -0.299974 -0.150114)
			(end -0.299974 0.150114)
			(stroke
				(width 0.1)
				(type default)
			)
			(layer "B.Fab")
		)
		(fp_line
			(start 0.299974 0.150114)
			(end 0.299974 -0.150114)
			(stroke
				(width 0.1)
				(type default)
			)
			(layer "B.Fab")
		)
		(fp_line
			(start -0.299974 0.150114)
			(end 0.299974 0.150114)
			(stroke
				(width 0.1)
				(type default)
			)
			(layer "B.Fab")
		)
		(pad "1" smd rect
			(at 0.2667 0 270)
			(size 0.3048 0.381)
			(layers "B.Cu" "B.Mask" "B.Paste")
			(net "P1V8_CPU0_RT2_1A_1D")
		)
		(pad "2" smd rect
			(at -0.2667 0 270)
			(size 0.3048 0.381)
			(layers "B.Cu" "B.Mask" "B.Paste")
			(net "GND")
		)
	)
	(footprint ""
		(layer "B.Cu")
		(at 183.946292 -351.21342 90)
		(property "Reference" "PC513_1"
			(at 0 0 90)
			(layer "B.SilkS")
			(hide yes)
			(effects
				(font
					(size 1.27 1.27)
				)
				(justify mirror)
			)
		)
		(property "Value" ""
			(at 0 0 90)
			(layer "B.Fab")
			(effects
				(font
					(size 1.27 1.27)
				)
				(justify mirror)
			)
		)
		(duplicate_pad_numbers_are_jumpers no)
		(fp_line
			(start 1.524 -0.762)
			(end -1.524 -0.762)
			(stroke
				(width 0.1524)
				(type default)
			)
			(layer "B.SilkS")
		)
		(fp_line
			(start -1.524 -0.762)
			(end -1.524 0.762)
			(stroke
				(width 0.1524)
				(type default)
			)
			(layer "B.SilkS")
		)
		(fp_line
			(start 1.524 0.762)
			(end 1.524 -0.762)
			(stroke
				(width 0.1524)
				(type default)
			)
			(layer "B.SilkS")
		)
		(fp_line
			(start -1.524 0.762)
			(end 1.524 0.762)
			(stroke
				(width 0.1524)
				(type default)
			)
			(layer "B.SilkS")
		)
		(fp_line
			(start 1.1049 -0.724916)
			(end 1.1049 0.724916)
			(stroke
				(width 0.1)
				(type default)
			)
			(layer "B.Fab")
		)
		(fp_line
			(start -1.1049 -0.724916)
			(end 1.1049 -0.724916)
			(stroke
				(width 0.1)
				(type default)
			)
			(layer "B.Fab")
		)
		(fp_line
			(start 1.1049 0.724916)
			(end -1.1049 0.724916)
			(stroke
				(width 0.1)
				(type default)
			)
			(layer "B.Fab")
		)
		(fp_line
			(start -1.1049 0.724916)
			(end -1.1049 -0.724916)
			(stroke
				(width 0.1)
				(type default)
			)
			(layer "B.Fab")
		)
		(pad "1" smd rect
			(at 0.889 0 90)
			(size 1.016 1.27)
			(layers "B.Cu" "B.Mask" "B.Paste")
			(net "SW_P12V_AUX_PVDD11_S3_P1_FLT")
		)
		(pad "2" smd rect
			(at -0.889 0 90)
			(size 1.016 1.27)
			(layers "B.Cu" "B.Mask" "B.Paste")
			(net "GND")
		)
	)
	(footprint ""
		(layer "B.Cu")
		(at 428.98695 -37.023548 180)
		(property "Reference" "R6107"
			(at 0 0 0)
			(layer "B.SilkS")
			(hide yes)
			(effects
				(font
					(size 1.27 1.27)
				)
				(justify mirror)
			)
		)
		(property "Value" ""
			(at 0 0 0)
			(layer "B.Fab")
			(effects
				(font
					(size 1.27 1.27)
				)
				(justify mirror)
			)
		)
		(duplicate_pad_numbers_are_jumpers no)
		(fp_line
			(start 0.7874 0.4064)
			(end 0.7874 -0.4064)
			(stroke
				(width 0.1524)
				(type default)
			)
			(layer "B.SilkS")
		)
		(fp_line
			(start 0.7874 -0.4064)
			(end -0.7874 -0.4064)
			(stroke
				(width 0.1524)
				(type default)
			)
			(layer "B.SilkS")
		)
		(fp_line
			(start -0.7874 0.4064)
			(end 0.7874 0.4064)
			(stroke
				(width 0.1524)
				(type default)
			)
			(layer "B.SilkS")
		)
		(fp_line
			(start -0.7874 -0.4064)
			(end -0.7874 0.4064)
			(stroke
				(width 0.1524)
				(type default)
			)
			(layer "B.SilkS")
		)
		(fp_line
			(start 0.67945 0.3048)
			(end 0.67945 -0.305054)
			(stroke
				(width 0.1)
				(type default)
			)
			(layer "B.Fab")
		)
		(fp_line
			(start 0.67945 -0.305054)
			(end 0.12065 -0.305054)
			(stroke
				(width 0.1)
				(type default)
			)
			(layer "B.Fab")
		)
		(fp_line
			(start 0.12065 0.3048)
			(end 0.67945 0.3048)
			(stroke
				(width 0.1)
				(type default)
			)
			(layer "B.Fab")
		)
		(fp_line
			(start 0.12065 0.2794)
			(end 0.12065 0.3048)
			(stroke
				(width 0.1)
				(type default)
			)
			(layer "B.Fab")
		)
		(fp_line
			(start 0.12065 -0.2794)
			(end -0.12065 -0.2794)
			(stroke
				(width 0.1)
				(type default)
			)
			(layer "B.Fab")
		)
		(fp_line
			(start 0.12065 -0.305054)
			(end 0.12065 -0.2794)
			(stroke
				(width 0.1)
				(type default)
			)
			(layer "B.Fab")
		)
		(fp_line
			(start -0.120396 0.3048)
			(end -0.120396 0.2794)
			(stroke
				(width 0.1)
				(type default)
			)
			(layer "B.Fab")
		)
		(fp_line
			(start -0.120396 0.2794)
			(end 0.12065 0.2794)
			(stroke
				(width 0.1)
				(type default)
			)
			(layer "B.Fab")
		)
		(fp_line
			(start -0.12065 -0.2794)
			(end -0.12065 -0.3048)
			(stroke
				(width 0.1)
				(type default)
			)
			(layer "B.Fab")
		)
		(fp_line
			(start -0.12065 -0.3048)
			(end -0.67945 -0.3048)
			(stroke
				(width 0.1)
				(type default)
			)
			(layer "B.Fab")
		)
		(fp_line
			(start -0.67945 0.3048)
			(end -0.120396 0.3048)
			(stroke
				(width 0.1)
				(type default)
			)
			(layer "B.Fab")
		)
		(fp_line
			(start -0.67945 -0.3048)
			(end -0.67945 0.3048)
			(stroke
				(width 0.1)
				(type default)
			)
			(layer "B.Fab")
		)
		(pad "1" smd circle
			(at 0.40005 0)
			(size 0 0)
			(layers "B.Cu" "B.Mask" "B.Paste")
			(net "PVDD18_S5_P0")
		)
		(pad "2" smd circle
			(at -0.40005 0)
			(size 0 0)
			(layers "B.Cu" "B.Mask" "B.Paste")
			(net "BIOS_DEBUG_MODE")
		)
	)
	(footprint ""
		(layer "B.Cu")
		(at 335.918556 -398.942052 90)
		(property "Reference" "C645"
			(at 0 0 90)
			(layer "B.SilkS")
			(hide yes)
			(effects
				(font
					(size 1.27 1.27)
				)
				(justify mirror)
			)
		)
		(property "Value" ""
			(at 0 0 90)
			(layer "B.Fab")
			(effects
				(font
					(size 1.27 1.27)
				)
				(justify mirror)
			)
		)
		(duplicate_pad_numbers_are_jumpers no)
		(fp_line
			(start 0.7874 -0.4064)
			(end -0.7874 -0.4064)
			(stroke
				(width 0.1524)
				(type default)
			)
			(layer "B.SilkS")
		)
		(fp_line
			(start -0.7874 -0.4064)
			(end -0.7874 0.4064)
			(stroke
				(width 0.1524)
				(type default)
			)
			(layer "B.SilkS")
		)
		(fp_line
			(start 0.7874 0.4064)
			(end 0.7874 -0.4064)
			(stroke
				(width 0.1524)
				(type default)
			)
			(layer "B.SilkS")
		)
		(fp_line
			(start -0.7874 0.4064)
			(end 0.7874 0.4064)
			(stroke
				(width 0.1524)
				(type default)
			)
			(layer "B.SilkS")
		)
		(fp_line
			(start 0.67945 -0.305054)
			(end 0.12065 -0.305054)
			(stroke
				(width 0.1)
				(type default)
			)
			(layer "B.Fab")
		)
		(fp_line
			(start 0.12065 -0.305054)
			(end 0.12065 -0.2794)
			(stroke
				(width 0.1)
				(type default)
			)
			(layer "B.Fab")
		)
		(fp_line
			(start -0.12065 -0.3048)
			(end -0.67945 -0.3048)
			(stroke
				(width 0.1)
				(type default)
			)
			(layer "B.Fab")
		)
		(fp_line
			(start -0.67945 -0.3048)
			(end -0.67945 0.3048)
			(stroke
				(width 0.1)
				(type default)
			)
			(layer "B.Fab")
		)
		(fp_line
			(start 0.12065 -0.2794)
			(end -0.12065 -0.2794)
			(stroke
				(width 0.1)
				(type default)
			)
			(layer "B.Fab")
		)
		(fp_line
			(start -0.12065 -0.2794)
			(end -0.12065 -0.3048)
			(stroke
				(width 0.1)
				(type default)
			)
			(layer "B.Fab")
		)
		(fp_line
			(start 0.12065 0.2794)
			(end 0.12065 0.3048)
			(stroke
				(width 0.1)
				(type default)
			)
			(layer "B.Fab")
		)
		(fp_line
			(start -0.120396 0.2794)
			(end 0.12065 0.2794)
			(stroke
				(width 0.1)
				(type default)
			)
			(layer "B.Fab")
		)
		(fp_line
			(start 0.67945 0.3048)
			(end 0.67945 -0.305054)
			(stroke
				(width 0.1)
				(type default)
			)
			(layer "B.Fab")
		)
		(fp_line
			(start 0.12065 0.3048)
			(end 0.67945 0.3048)
			(stroke
				(width 0.1)
				(type default)
			)
			(layer "B.Fab")
		)
		(fp_line
			(start -0.120396 0.3048)
			(end -0.120396 0.2794)
			(stroke
				(width 0.1)
				(type default)
			)
			(layer "B.Fab")
		)
		(fp_line
			(start -0.67945 0.3048)
			(end -0.120396 0.3048)
			(stroke
				(width 0.1)
				(type default)
			)
			(layer "B.Fab")
		)
		(pad "1" smd circle
			(at 0.40005 0 270)
			(size 0 0)
			(layers "B.Cu" "B.Mask" "B.Paste")
			(net "P0V9_CPU0_RT1_2A")
		)
		(pad "2" smd circle
			(at -0.40005 0 270)
			(size 0 0)
			(layers "B.Cu" "B.Mask" "B.Paste")
			(net "GND")
		)
	)
)
